(kicad_pcb
	(version 20260206)
	(generator "pcbnew")
	(generator_version "10.0")
	(general
		(thickness 1.6)
		(legacy_teardrops no)
	)
	(paper "A4")
	(title_block
		(title "Wiwynn_Tioga_Pass_MB.brd")
		(comment 1 "Tioga Pass / footprints 1198-1204 of 4770")
	)
	(layers
		(0 "F.Cu" signal "TOP")
		(4 "In1.Cu" signal "L2GND")
		(6 "In2.Cu" signal "L3")
		(8 "In3.Cu" signal "L4GND")
		(10 "In4.Cu" signal "L5")
		(12 "In5.Cu" signal "L6GND")
		(14 "In6.Cu" signal "L7VCC")
		(16 "In7.Cu" signal "L8VCC")
		(18 "In8.Cu" signal "L9GND")
		(20 "In9.Cu" signal "L10")
		(22 "In10.Cu" signal "L11GND")
		(24 "In11.Cu" signal "L12")
		(26 "In12.Cu" signal "L13GND")
		(2 "B.Cu" signal "BOTTOM")
		(9 "F.Adhes" user "F.Adhesive")
		(11 "B.Adhes" user "B.Adhesive")
		(13 "F.Paste" user "Package Geometry/Pastemask Top")
		(15 "B.Paste" user "Package Geometry/Pastemask Bottom")
		(5 "F.SilkS" user "Ref Des/Silkscreen Top")
		(7 "B.SilkS" user "Ref Des/Silkscreen Bottom")
		(1 "F.Mask" user "Board Geometry/Soldermask Top")
		(3 "B.Mask" user "Board Geometry/Soldermask Bottom")
		(17 "Dwgs.User" user "User.Drawings")
		(19 "Cmts.User" user "User.Comments")
		(21 "Eco1.User" user "User.Eco1")
		(23 "Eco2.User" user "User.Eco2")
		(25 "Edge.Cuts" user "Board Geometry/Outline")
		(27 "Margin" user)
		(31 "F.CrtYd" user "Package Geometry/Place Bound Top")
		(29 "B.CrtYd" user "Package Geometry/Place Bound Bottom")
		(35 "F.Fab" user "Ref Des/Assembly Top")
		(33 "B.Fab" user "Ref Des/Assembly Bottom")
	)
	(footprint ""
		(layer "F.Cu")
		(at 166.624 -150.241 90)
		(property "Reference" "R4A3"
			(at 0 0 90)
			(layer "F.SilkS")
			(hide yes)
			(effects
				(font
					(size 1.27 1.27)
				)
			)
		)
		(property "Value" ""
			(at 0 0 90)
			(layer "F.Fab")
			(effects
				(font
					(size 1.27 1.27)
				)
			)
		)
		(duplicate_pad_numbers_are_jumpers no)
		(fp_poly
			(pts
				(xy -0.2794 -0.1016) (xy 0.2794 -0.1016) (xy 0.2794 0.9906) (xy -0.2794 0.9906)
			)
			(stroke
				(width 0)
				(type default)
			)
			(fill no)
			(layer "F.CrtYd")
		)
		(fp_line
			(start 0.2794 -0.1016)
			(end -0.2794 -0.1016)
			(stroke
				(width 0.1)
				(type default)
			)
			(layer "F.Fab")
		)
		(fp_line
			(start -0.2794 -0.1016)
			(end -0.2794 0.9906)
			(stroke
				(width 0.1)
				(type default)
			)
			(layer "F.Fab")
		)
		(fp_line
			(start 0.2794 0.9906)
			(end 0.2794 -0.1016)
			(stroke
				(width 0.1)
				(type default)
			)
			(layer "F.Fab")
		)
		(fp_line
			(start -0.2794 0.9906)
			(end 0.2794 0.9906)
			(stroke
				(width 0.1)
				(type default)
			)
			(layer "F.Fab")
		)
		(pad "1" smd rect
			(at 0 0 90)
			(size 0.508 0.508)
			(layers "F.Cu" "F.Mask" "F.Paste")
			(net "PWRGD_PVDDQ_KLM_R")
		)
		(pad "2" smd rect
			(at 0 0.889 90)
			(size 0.508 0.508)
			(layers "F.Cu" "F.Mask" "F.Paste")
			(net "FM_PVTT_KLM_EN_R")
		)
		(zone
			(layer "F.Cu")
			(hatch none 0.5)
			(connect_pads
				(clearance 0)
			)
			(min_thickness 0.25)
			(keepout
				(tracks allowed)
				(vias not_allowed)
				(pads allowed)
				(copperpour not_allowed)
				(footprints allowed)
			)
			(placement
				(enabled no)
				(sheetname "")
			)
			(fill
				(thermal_gap 0.5)
				(thermal_bridge_width 0.5)
				(island_removal_mode 0)
			)
			(polygon
				(pts
					(xy 166.878 -149.987) (xy 166.878 -150.495) (xy 167.259 -150.495) (xy 167.259 -149.987)
				)
			)
		)
		(zone
			(layer "F.Cu")
			(hatch none 0.5)
			(connect_pads
				(clearance 0)
			)
			(min_thickness 0.25)
			(keepout
				(tracks not_allowed)
				(vias allowed)
				(pads allowed)
				(copperpour not_allowed)
				(footprints allowed)
			)
			(placement
				(enabled no)
				(sheetname "")
			)
			(fill
				(thermal_gap 0.5)
				(thermal_bridge_width 0.5)
				(island_removal_mode 0)
			)
			(polygon
				(pts
					(xy 167.259 -149.987) (xy 167.259 -150.495) (xy 166.878 -150.495) (xy 166.878 -149.987)
				)
			)
		)
	)
	(footprint ""
		(layer "F.Cu")
		(at 406.172416 -149.452584 -90)
		(property "Reference" "R8A10"
			(at 0 0 270)
			(layer "F.SilkS")
			(hide yes)
			(effects
				(font
					(size 1.27 1.27)
				)
			)
		)
		(property "Value" ""
			(at 0 0 270)
			(layer "F.Fab")
			(effects
				(font
					(size 1.27 1.27)
				)
			)
		)
		(duplicate_pad_numbers_are_jumpers no)
		(fp_poly
			(pts
				(xy -0.2794 -0.1016) (xy 0.2794 -0.1016) (xy 0.2794 0.9906) (xy -0.2794 0.9906)
			)
			(stroke
				(width 0)
				(type default)
			)
			(fill no)
			(layer "F.CrtYd")
		)
		(fp_line
			(start -0.2794 0.9906)
			(end 0.2794 0.9906)
			(stroke
				(width 0.1)
				(type default)
			)
			(layer "F.Fab")
		)
		(fp_line
			(start 0.2794 0.9906)
			(end 0.2794 -0.1016)
			(stroke
				(width 0.1)
				(type default)
			)
			(layer "F.Fab")
		)
		(fp_line
			(start -0.2794 -0.1016)
			(end -0.2794 0.9906)
			(stroke
				(width 0.1)
				(type default)
			)
			(layer "F.Fab")
		)
		(fp_line
			(start 0.2794 -0.1016)
			(end -0.2794 -0.1016)
			(stroke
				(width 0.1)
				(type default)
			)
			(layer "F.Fab")
		)
		(pad "1" smd rect
			(at 0 0 270)
			(size 0.508 0.508)
			(layers "F.Cu" "F.Mask" "F.Paste")
			(net "P3V3_STBY")
		)
		(pad "2" smd rect
			(at 0 0.889 270)
			(size 0.508 0.508)
			(layers "F.Cu" "F.Mask" "F.Paste")
			(net "PWRGD_P1V8_PCH_STBY_R")
		)
		(zone
			(layer "F.Cu")
			(hatch none 0.5)
			(connect_pads
				(clearance 0)
			)
			(min_thickness 0.25)
			(keepout
				(tracks not_allowed)
				(vias allowed)
				(pads allowed)
				(copperpour not_allowed)
				(footprints allowed)
			)
			(placement
				(enabled no)
				(sheetname "")
			)
			(fill
				(thermal_gap 0.5)
				(thermal_bridge_width 0.5)
				(island_removal_mode 0)
			)
			(polygon
				(pts
					(xy 405.537416 -149.706584) (xy 405.537416 -149.198584) (xy 405.918416 -149.198584) (xy 405.918416 -149.706584)
				)
			)
		)
		(zone
			(layer "F.Cu")
			(hatch none 0.5)
			(connect_pads
				(clearance 0)
			)
			(min_thickness 0.25)
			(keepout
				(tracks allowed)
				(vias not_allowed)
				(pads allowed)
				(copperpour not_allowed)
				(footprints allowed)
			)
			(placement
				(enabled no)
				(sheetname "")
			)
			(fill
				(thermal_gap 0.5)
				(thermal_bridge_width 0.5)
				(island_removal_mode 0)
			)
			(polygon
				(pts
					(xy 405.918416 -149.706584) (xy 405.918416 -149.198584) (xy 405.537416 -149.198584) (xy 405.537416 -149.706584)
				)
			)
		)
	)
	(footprint ""
		(layer "F.Cu")
		(at 197.226428 -93.734382 -90)
		(property "Reference" "C4C6"
			(at 0 0 270)
			(layer "F.SilkS")
			(hide yes)
			(effects
				(font
					(size 1.27 1.27)
				)
			)
		)
		(property "Value" ""
			(at 0 0 270)
			(layer "F.Fab")
			(effects
				(font
					(size 1.27 1.27)
				)
			)
		)
		(duplicate_pad_numbers_are_jumpers no)
		(fp_poly
			(pts
				(xy 0.3048 -0.1016) (xy 0.3048 0.9906) (xy -0.3048 0.9906) (xy -0.3048 -0.1016)
			)
			(stroke
				(width 0)
				(type default)
			)
			(fill no)
			(layer "F.CrtYd")
		)
		(fp_line
			(start -0.3048 0.9906)
			(end 0.3048 0.9906)
			(stroke
				(width 0.1)
				(type default)
			)
			(layer "F.Fab")
		)
		(fp_line
			(start 0.3048 0.9906)
			(end 0.3048 -0.1016)
			(stroke
				(width 0.1)
				(type default)
			)
			(layer "F.Fab")
		)
		(fp_line
			(start -0.3048 -0.1016)
			(end -0.3048 0.9906)
			(stroke
				(width 0.1)
				(type default)
			)
			(layer "F.Fab")
		)
		(fp_line
			(start 0.3048 -0.1016)
			(end -0.3048 -0.1016)
			(stroke
				(width 0.1)
				(type default)
			)
			(layer "F.Fab")
		)
		(pad "1" smd rect
			(at 0 0 270)
			(size 0.508 0.508)
			(layers "F.Cu" "F.Mask" "F.Paste")
			(net "VR_PVSA_CPU0_VCIN")
		)
		(pad "2" smd rect
			(at 0 0.889 270)
			(size 0.508 0.508)
			(layers "F.Cu" "F.Mask" "F.Paste")
			(net "GND")
		)
		(zone
			(layer "F.Cu")
			(hatch none 0.5)
			(connect_pads
				(clearance 0)
			)
			(min_thickness 0.25)
			(keepout
				(tracks not_allowed)
				(vias allowed)
				(pads allowed)
				(copperpour not_allowed)
				(footprints allowed)
			)
			(placement
				(enabled no)
				(sheetname "")
			)
			(fill
				(thermal_gap 0.5)
				(thermal_bridge_width 0.5)
				(island_removal_mode 0)
			)
			(polygon
				(pts
					(xy 196.591428 -93.988382) (xy 196.591428 -93.480382) (xy 196.972428 -93.480382) (xy 196.972428 -93.988382)
				)
			)
		)
		(zone
			(layer "F.Cu")
			(hatch none 0.5)
			(connect_pads
				(clearance 0)
			)
			(min_thickness 0.25)
			(keepout
				(tracks allowed)
				(vias not_allowed)
				(pads allowed)
				(copperpour not_allowed)
				(footprints allowed)
			)
			(placement
				(enabled no)
				(sheetname "")
			)
			(fill
				(thermal_gap 0.5)
				(thermal_bridge_width 0.5)
				(island_removal_mode 0)
			)
			(polygon
				(pts
					(xy 196.972428 -93.988382) (xy 196.972428 -93.480382) (xy 196.591428 -93.480382) (xy 196.591428 -93.988382)
				)
			)
		)
	)
	(footprint ""
		(layer "F.Cu")
		(at 368.808 -137.3124)
		(property "Reference" "R7A13"
			(at 0 0 0)
			(layer "F.SilkS")
			(hide yes)
			(effects
				(font
					(size 1.27 1.27)
				)
			)
		)
		(property "Value" ""
			(at 0 0 0)
			(layer "F.Fab")
			(effects
				(font
					(size 1.27 1.27)
				)
			)
		)
		(duplicate_pad_numbers_are_jumpers no)
		(fp_poly
			(pts
				(xy -0.2794 -0.1016) (xy 0.2794 -0.1016) (xy 0.2794 0.9906) (xy -0.2794 0.9906)
			)
			(stroke
				(width 0)
				(type default)
			)
			(fill no)
			(layer "F.CrtYd")
		)
		(fp_line
			(start -0.2794 -0.1016)
			(end -0.2794 0.9906)
			(stroke
				(width 0.1)
				(type default)
			)
			(layer "F.Fab")
		)
		(fp_line
			(start -0.2794 0.9906)
			(end 0.2794 0.9906)
			(stroke
				(width 0.1)
				(type default)
			)
			(layer "F.Fab")
		)
		(fp_line
			(start 0.2794 -0.1016)
			(end -0.2794 -0.1016)
			(stroke
				(width 0.1)
				(type default)
			)
			(layer "F.Fab")
		)
		(fp_line
			(start 0.2794 0.9906)
			(end 0.2794 -0.1016)
			(stroke
				(width 0.1)
				(type default)
			)
			(layer "F.Fab")
		)
		(pad "1" smd rect
			(at 0 0)
			(size 0.508 0.508)
			(layers "F.Cu" "F.Mask" "F.Paste")
			(net "VSENSE_PVNN_PCH_STBY_AVSP")
		)
		(pad "2" smd rect
			(at 0 0.889)
			(size 0.508 0.508)
			(layers "F.Cu" "F.Mask" "F.Paste")
			(net "PVNN_PCH_STBY")
		)
		(zone
			(layer "F.Cu")
			(hatch none 0.5)
			(connect_pads
				(clearance 0)
			)
			(min_thickness 0.25)
			(keepout
				(tracks allowed)
				(vias not_allowed)
				(pads allowed)
				(copperpour not_allowed)
				(footprints allowed)
			)
			(placement
				(enabled no)
				(sheetname "")
			)
			(fill
				(thermal_gap 0.5)
				(thermal_bridge_width 0.5)
				(island_removal_mode 0)
			)
			(polygon
				(pts
					(xy 368.554 -137.0584) (xy 369.062 -137.0584) (xy 369.062 -136.6774) (xy 368.554 -136.6774)
				)
			)
		)
		(zone
			(layer "F.Cu")
			(hatch none 0.5)
			(connect_pads
				(clearance 0)
			)
			(min_thickness 0.25)
			(keepout
				(tracks not_allowed)
				(vias allowed)
				(pads allowed)
				(copperpour not_allowed)
				(footprints allowed)
			)
			(placement
				(enabled no)
				(sheetname "")
			)
			(fill
				(thermal_gap 0.5)
				(thermal_bridge_width 0.5)
				(island_removal_mode 0)
			)
			(polygon
				(pts
					(xy 368.554 -136.6774) (xy 369.062 -136.6774) (xy 369.062 -137.0584) (xy 368.554 -137.0584)
				)
			)
		)
	)
	(footprint ""
		(layer "F.Cu")
		(at 0 -155.10002 90)
		(property "Reference" "TH1A1"
			(at 2.45491 8.6868 0)
			(unlocked yes)
			(layer "F.SilkS")
			(effects
				(font
					(size 0.7874 0.5842)
					(thickness 0.1524)
				)
				(justify left)
			)
		)
		(property "Value" ""
			(at 0 0 90)
			(layer "F.Fab")
			(effects
				(font
					(size 1.27 1.27)
				)
			)
		)
		(duplicate_pad_numbers_are_jumpers no)
		(fp_poly
			(pts
				(arc
					(start 3.0226 0.68834)
					(mid 3.042235 0.827855)
					(end 3.099562 0.956564)
				)
				(arc
					(start 3.099562 0.956564)
					(mid 4.012804 3.550073)
					(end 3.042158 6.12267)
				)
				(arc
					(start 3.042158 6.12267)
					(mid 0 7.518589)
					(end -3.042158 6.12267)
				)
				(arc
					(start -3.042158 6.12267)
					(mid -4.012854 3.55061)
					(end -3.100324 0.957326)
				)
				(arc
					(start -3.100324 0.957326)
					(mid -3.042498 0.827518)
					(end -3.0226 0.686816)
				)
				(arc
					(start -3.0226 -0.000254)
					(mid -2.137121 -2.137227)
					(end 0 -3.022346)
				)
				(arc
					(start 0 -3.022346)
					(mid 2.137227 -2.136973)
					(end 3.0226 0.000254)
				)
			)
			(stroke
				(width 0)
				(type default)
			)
			(fill no)
			(layer "F.CrtYd")
		)
		(pad "1" thru_hole custom
			(at 0 0 90)
			(size 2.00667 2.00667)
			(drill 0.3048)
			(layers "*.Cu" "*.Mask")
			(remove_unused_layers no)
			(net "GND")
			(clearance -0.889)
			(options
				(clearance outline)
				(anchor circle)
			)
			(primitives
				(gr_poly
					(pts
						(arc
							(start 3.042158 3.874516)
							(mid 0 5.270435)
							(end -3.042158 3.874516)
						)
						(arc
							(start -3.042158 3.874516)
							(mid -4.012854 1.302456)
							(end -3.100324 -1.290828)
						)
						(arc
							(start -3.100324 -1.290828)
							(mid -3.042498 -1.420636)
							(end -3.0226 -1.561338)
						)
						(arc
							(start -3.0226 -2.248408)
							(mid -2.137121 -4.385381)
							(end 0 -5.2705)
						)
						(arc
							(start 0 -5.2705)
							(mid 2.137227 -4.385127)
							(end 3.0226 -2.2479)
						)
						(arc
							(start 3.0226 -1.55956)
							(mid 3.04227 -1.420177)
							(end 3.099562 -1.29159)
						)
						(arc
							(start 3.099562 -1.29159)
							(mid 4.012804 1.301919)
							(end 3.042158 3.874516)
						)
					)
					(width 0)
					(fill yes)
				)
			)
		)
	)
	(footprint ""
		(layer "F.Cu")
		(at 39.6748 -49.6824 90)
		(property "Reference" "R1E7"
			(at 0 0 90)
			(layer "F.SilkS")
			(hide yes)
			(effects
				(font
					(size 1.27 1.27)
				)
			)
		)
		(property "Value" ""
			(at 0 0 90)
			(layer "F.Fab")
			(effects
				(font
					(size 1.27 1.27)
				)
			)
		)
		(duplicate_pad_numbers_are_jumpers no)
		(fp_poly
			(pts
				(xy -0.2794 -0.1016) (xy 0.2794 -0.1016) (xy 0.2794 0.9906) (xy -0.2794 0.9906)
			)
			(stroke
				(width 0)
				(type default)
			)
			(fill no)
			(layer "F.CrtYd")
		)
		(fp_line
			(start 0.2794 -0.1016)
			(end -0.2794 -0.1016)
			(stroke
				(width 0.1)
				(type default)
			)
			(layer "F.Fab")
		)
		(fp_line
			(start -0.2794 -0.1016)
			(end -0.2794 0.9906)
			(stroke
				(width 0.1)
				(type default)
			)
			(layer "F.Fab")
		)
		(fp_line
			(start 0.2794 0.9906)
			(end 0.2794 -0.1016)
			(stroke
				(width 0.1)
				(type default)
			)
			(layer "F.Fab")
		)
		(fp_line
			(start -0.2794 0.9906)
			(end 0.2794 0.9906)
			(stroke
				(width 0.1)
				(type default)
			)
			(layer "F.Fab")
		)
		(pad "1" smd rect
			(at 0 0 90)
			(size 0.508 0.508)
			(layers "F.Cu" "F.Mask" "F.Paste")
			(net "VSENSE_PVCCIN_CPU1_N")
		)
		(pad "2" smd rect
			(at 0 0.889 90)
			(size 0.508 0.508)
			(layers "F.Cu" "F.Mask" "F.Paste")
			(net "VSENSE_PVCCIN_CPU1_SKT_VRTN")
		)
		(zone
			(layer "F.Cu")
			(hatch none 0.5)
			(connect_pads
				(clearance 0)
			)
			(min_thickness 0.25)
			(keepout
				(tracks allowed)
				(vias not_allowed)
				(pads allowed)
				(copperpour not_allowed)
				(footprints allowed)
			)
			(placement
				(enabled no)
				(sheetname "")
			)
			(fill
				(thermal_gap 0.5)
				(thermal_bridge_width 0.5)
				(island_removal_mode 0)
			)
			(polygon
				(pts
					(xy 39.9288 -49.4284) (xy 39.9288 -49.9364) (xy 40.3098 -49.9364) (xy 40.3098 -49.4284)
				)
			)
		)
		(zone
			(layer "F.Cu")
			(hatch none 0.5)
			(connect_pads
				(clearance 0)
			)
			(min_thickness 0.25)
			(keepout
				(tracks not_allowed)
				(vias allowed)
				(pads allowed)
				(copperpour not_allowed)
				(footprints allowed)
			)
			(placement
				(enabled no)
				(sheetname "")
			)
			(fill
				(thermal_gap 0.5)
				(thermal_bridge_width 0.5)
				(island_removal_mode 0)
			)
			(polygon
				(pts
					(xy 40.3098 -49.4284) (xy 40.3098 -49.9364) (xy 39.9288 -49.9364) (xy 39.9288 -49.4284)
				)
			)
		)
	)
	(footprint ""
		(layer "F.Cu")
		(at 14.224 -69.977 90)
		(property "Reference" "R1D44"
			(at 0 0 90)
			(layer "F.SilkS")
			(hide yes)
			(effects
				(font
					(size 1.27 1.27)
				)
			)
		)
		(property "Value" ""
			(at 0 0 90)
			(layer "F.Fab")
			(effects
				(font
					(size 1.27 1.27)
				)
			)
		)
		(duplicate_pad_numbers_are_jumpers no)
		(fp_rect
			(start -0.2794 0.9906)
			(end 0.2794 -0.1016)
			(stroke
				(width 0)
				(type default)
			)
			(fill no)
			(layer "F.CrtYd")
		)
		(fp_line
			(start 0.2794 -0.1016)
			(end -0.2794 -0.1016)
			(stroke
				(width 0.1)
				(type default)
			)
			(layer "F.Fab")
		)
		(fp_line
			(start -0.2794 -0.1016)
			(end -0.2794 0.9906)
			(stroke
				(width 0.1)
				(type default)
			)
			(layer "F.Fab")
		)
		(fp_line
			(start 0.2794 0.9906)
			(end 0.2794 -0.1016)
			(stroke
				(width 0.1)
				(type default)
			)
			(layer "F.Fab")
		)
		(fp_line
			(start -0.2794 0.9906)
			(end 0.2794 0.9906)
			(stroke
				(width 0.1)
				(type default)
			)
			(layer "F.Fab")
		)
		(pad "1" smd rect
			(at 0 0 90)
			(size 0.508 0.508)
			(layers "F.Cu" "F.Mask" "F.Paste")
			(net "A_HSC_MOP")
		)
		(pad "2" smd rect
			(at 0 0.889 90)
			(size 0.508 0.508)
			(layers "F.Cu" "F.Mask" "F.Paste")
			(net "A_HSC_HSP")
		)
		(zone
			(layer "F.Cu")
			(hatch none 0.5)
			(connect_pads
				(clearance 0)
			)
			(min_thickness 0.25)
			(keepout
				(tracks not_allowed)
				(vias allowed)
				(pads allowed)
				(copperpour not_allowed)
				(footprints allowed)
			)
			(placement
				(enabled no)
				(sheetname "")
			)
			(fill
				(thermal_gap 0.5)
				(thermal_bridge_width 0.5)
				(island_removal_mode 0)
			)
			(polygon
				(pts
					(xy 14.859 -69.723) (xy 14.859 -70.231) (xy 14.478 -70.231) (xy 14.478 -69.723)
				)
			)
		)
		(zone
			(layer "F.Cu")
			(hatch none 0.5)
			(connect_pads
				(clearance 0)
			)
			(min_thickness 0.25)
			(keepout
				(tracks allowed)
				(vias not_allowed)
				(pads allowed)
				(copperpour not_allowed)
				(footprints allowed)
			)
			(placement
				(enabled no)
				(sheetname "")
			)
			(fill
				(thermal_gap 0.5)
				(thermal_bridge_width 0.5)
				(island_removal_mode 0)
			)
			(polygon
				(pts
					(xy 14.859 -69.723) (xy 14.859 -70.231) (xy 14.478 -70.231) (xy 14.478 -69.723)
				)
			)
		)
	)
)
